# BASEBOARD_FAB2 (Tioga Pass) — schematic netlist excerpt (pin names and nets, part order shuffled) for the footprints in the layout excerpt that follows; sources: Cadence DE-HDL packaged netlist, KiCad conversion of Wiwynn_Tioga_Pass_MB.brd

C1R1  CAP  0.22UF 16V 10% X7R  pkg 0402  page 106 : A = P3E_CPU0_PE3_OCP_TXN<0> ; B = P3E_OCP_CPU0_PE3_C_TXN<0>
C3L11  CAP  10UF 16V 10% X6S  pkg 0805  page 236 : A = VR_FET_SW_P12V_STBY_PVDDQ_DEF ; B = GND
R7E10  RES  4.75K 1% CHIP  pkg 0402  page 95 : A = P3V3 ; B = IRQ_CPU0_VRHOT

(kicad_pcb
	(version 20260206)
	(generator "pcbnew")
	(generator_version "10.0")
	(general
		(thickness 1.6)
		(legacy_teardrops no)
	)
	(paper "A4")
	(title_block
		(title "Wiwynn_Tioga_Pass_MB.brd")
		(comment 1 "Tioga Pass / footprints 2467-2469 of 4770")
	)
	(layers
		(0 "F.Cu" signal "TOP")
		(4 "In1.Cu" signal "L2GND")
		(6 "In2.Cu" signal "L3")
		(8 "In3.Cu" signal "L4GND")
		(10 "In4.Cu" signal "L5")
		(12 "In5.Cu" signal "L6GND")
		(14 "In6.Cu" signal "L7VCC")
		(16 "In7.Cu" signal "L8VCC")
		(18 "In8.Cu" signal "L9GND")
		(20 "In9.Cu" signal "L10")
		(22 "In10.Cu" signal "L11GND")
		(24 "In11.Cu" signal "L12")
		(26 "In12.Cu" signal "L13GND")
		(2 "B.Cu" signal "BOTTOM")
		(9 "F.Adhes" user "F.Adhesive")
		(11 "B.Adhes" user "B.Adhesive")
		(13 "F.Paste" user "Package Geometry/Pastemask Top")
		(15 "B.Paste" user "Package Geometry/Pastemask Bottom")
		(5 "F.SilkS" user "Ref Des/Silkscreen Top")
		(7 "B.SilkS" user "Ref Des/Silkscreen Bottom")
		(1 "F.Mask" user "Board Geometry/Soldermask Top")
		(3 "B.Mask" user "Board Geometry/Soldermask Bottom")
		(17 "Dwgs.User" user "User.Drawings")
		(19 "Cmts.User" user "User.Comments")
		(21 "Eco1.User" user "User.Eco1")
		(23 "Eco2.User" user "User.Eco2")
		(25 "Edge.Cuts" user "Board Geometry/Outline")
		(27 "Margin" user)
		(31 "F.CrtYd" user "Package Geometry/Place Bound Top")
		(29 "B.CrtYd" user "Package Geometry/Place Bound Bottom")
		(35 "F.Fab" user "Ref Des/Assembly Top")
		(33 "B.Fab" user "Ref Des/Assembly Bottom")
	)
	(footprint ""
		(layer "B.Cu")
		(at 463.8294 -52.432458)
		(property "Reference" "C1R1"
			(at 0 0 0)
			(layer "B.SilkS")
			(hide yes)
			(effects
				(font
					(size 1.27 1.27)
				)
				(justify mirror)
			)
		)
		(property "Value" ""
			(at 0 0 0)
			(layer "B.Fab")
			(effects
				(font
					(size 1.27 1.27)
				)
				(justify mirror)
			)
		)
		(duplicate_pad_numbers_are_jumpers no)
		(fp_poly
			(pts
				(xy -0.3048 -0.1016) (xy -0.3048 0.9906) (xy 0.3048 0.9906) (xy 0.3048 -0.1016)
			)
			(stroke
				(width 0)
				(type default)
			)
			(fill no)
			(layer "B.CrtYd")
		)
		(fp_line
			(start -0.3048 -0.1016)
			(end 0.3048 -0.1016)
			(stroke
				(width 0.1)
				(type default)
			)
			(layer "B.Fab")
		)
		(fp_line
			(start -0.3048 0.9906)
			(end -0.3048 -0.1016)
			(stroke
				(width 0.1)
				(type default)
			)
			(layer "B.Fab")
		)
		(fp_line
			(start 0.3048 -0.1016)
			(end 0.3048 0.9906)
			(stroke
				(width 0.1)
				(type default)
			)
			(layer "B.Fab")
		)
		(fp_line
			(start 0.3048 0.9906)
			(end -0.3048 0.9906)
			(stroke
				(width 0.1)
				(type default)
			)
			(layer "B.Fab")
		)
		(pad "1" smd rect
			(at 0 0 180)
			(size 0.508 0.508)
			(layers "B.Cu" "B.Mask" "B.Paste")
			(net "P3E_CPU0_PE3_OCP_TXN<0>")
		)
		(pad "2" smd rect
			(at 0 0.889 180)
			(size 0.508 0.508)
			(layers "B.Cu" "B.Mask" "B.Paste")
			(net "P3E_OCP_CPU0_PE3_C_TXN<0>")
		)
		(zone
			(layer "B.Cu")
			(hatch none 0.5)
			(connect_pads
				(clearance 0)
			)
			(min_thickness 0.25)
			(keepout
				(tracks allowed)
				(vias not_allowed)
				(pads allowed)
				(copperpour not_allowed)
				(footprints allowed)
			)
			(placement
				(enabled no)
				(sheetname "")
			)
			(fill
				(thermal_gap 0.5)
				(thermal_bridge_width 0.5)
				(island_removal_mode 0)
			)
			(polygon
				(pts
					(xy 464.0834 -52.178458) (xy 463.5754 -52.178458) (xy 463.5754 -51.797458) (xy 464.0834 -51.797458)
				)
			)
		)
		(zone
			(layer "B.Cu")
			(hatch none 0.5)
			(connect_pads
				(clearance 0)
			)
			(min_thickness 0.25)
			(keepout
				(tracks not_allowed)
				(vias allowed)
				(pads allowed)
				(copperpour not_allowed)
				(footprints allowed)
			)
			(placement
				(enabled no)
				(sheetname "")
			)
			(fill
				(thermal_gap 0.5)
				(thermal_bridge_width 0.5)
				(island_removal_mode 0)
			)
			(polygon
				(pts
					(xy 464.0834 -51.797458) (xy 463.5754 -51.797458) (xy 463.5754 -52.178458) (xy 464.0834 -52.178458)
				)
			)
		)
	)
	(footprint ""
		(layer "B.Cu")
		(at 377.2281 -36.83 180)
		(property "Reference" "R7E10"
			(at 0 0 0)
			(layer "B.SilkS")
			(hide yes)
			(effects
				(font
					(size 1.27 1.27)
				)
				(justify mirror)
			)
		)
		(property "Value" ""
			(at 0 0 0)
			(layer "B.Fab")
			(effects
				(font
					(size 1.27 1.27)
				)
				(justify mirror)
			)
		)
		(duplicate_pad_numbers_are_jumpers no)
		(fp_poly
			(pts
				(xy 0.2794 -0.1016) (xy -0.2794 -0.1016) (xy -0.2794 0.9906) (xy 0.2794 0.9906)
			)
			(stroke
				(width 0)
				(type default)
			)
			(fill no)
			(layer "B.CrtYd")
		)
		(fp_line
			(start 0.2794 0.9906)
			(end -0.2794 0.9906)
			(stroke
				(width 0.1)
				(type default)
			)
			(layer "B.Fab")
		)
		(fp_line
			(start 0.2794 -0.1016)
			(end 0.2794 0.9906)
			(stroke
				(width 0.1)
				(type default)
			)
			(layer "B.Fab")
		)
		(fp_line
			(start -0.2794 0.9906)
			(end -0.2794 -0.1016)
			(stroke
				(width 0.1)
				(type default)
			)
			(layer "B.Fab")
		)
		(fp_line
			(start -0.2794 -0.1016)
			(end 0.2794 -0.1016)
			(stroke
				(width 0.1)
				(type default)
			)
			(layer "B.Fab")
		)
		(pad "1" smd rect
			(at 0 0)
			(size 0.508 0.508)
			(layers "B.Cu" "B.Mask" "B.Paste")
			(net "P3V3")
		)
		(pad "2" smd rect
			(at 0 0.889)
			(size 0.508 0.508)
			(layers "B.Cu" "B.Mask" "B.Paste")
			(net "IRQ_CPU0_VRHOT")
		)
		(zone
			(layer "B.Cu")
			(hatch none 0.5)
			(connect_pads
				(clearance 0)
			)
			(min_thickness 0.25)
			(keepout
				(tracks not_allowed)
				(vias allowed)
				(pads allowed)
				(copperpour not_allowed)
				(footprints allowed)
			)
			(placement
				(enabled no)
				(sheetname "")
			)
			(fill
				(thermal_gap 0.5)
				(thermal_bridge_width 0.5)
				(island_removal_mode 0)
			)
			(polygon
				(pts
					(xy 376.9741 -37.465) (xy 377.4821 -37.465) (xy 377.4821 -37.084) (xy 376.9741 -37.084)
				)
			)
		)
		(zone
			(layer "B.Cu")
			(hatch none 0.5)
			(connect_pads
				(clearance 0)
			)
			(min_thickness 0.25)
			(keepout
				(tracks allowed)
				(vias not_allowed)
				(pads allowed)
				(copperpour not_allowed)
				(footprints allowed)
			)
			(placement
				(enabled no)
				(sheetname "")
			)
			(fill
				(thermal_gap 0.5)
				(thermal_bridge_width 0.5)
				(island_removal_mode 0)
			)
			(polygon
				(pts
					(xy 376.9741 -37.084) (xy 377.4821 -37.084) (xy 377.4821 -37.465) (xy 376.9741 -37.465)
				)
			)
		)
	)
	(footprint ""
		(layer "B.Cu")
		(at 377.7488 -154.457146)
		(property "Reference" "C3L11"
			(at 0 0 0)
			(layer "B.SilkS")
			(hide yes)
			(effects
				(font
					(size 1.27 1.27)
				)
				(justify mirror)
			)
		)
		(property "Value" ""
			(at 0 0 0)
			(layer "B.Fab")
			(effects
				(font
					(size 1.27 1.27)
				)
				(justify mirror)
			)
		)
		(duplicate_pad_numbers_are_jumpers no)
		(fp_poly
			(pts
				(xy 0.7239 -0.2159) (xy -0.7239 -0.2159) (xy -0.7239 1.9939) (xy 0.7239 1.9939)
			)
			(stroke
				(width 0)
				(type default)
			)
			(fill no)
			(layer "B.CrtYd")
		)
		(fp_line
			(start -0.7239 -0.2159)
			(end 0.7239 -0.2159)
			(stroke
				(width 0.1)
				(type default)
			)
			(layer "B.Fab")
		)
		(fp_line
			(start -0.7239 1.9939)
			(end -0.7239 -0.2159)
			(stroke
				(width 0.1)
				(type default)
			)
			(layer "B.Fab")
		)
		(fp_line
			(start 0.7239 -0.2159)
			(end 0.7239 1.9939)
			(stroke
				(width 0.1)
				(type default)
			)
			(layer "B.Fab")
		)
		(fp_line
			(start 0.7239 1.9939)
			(end -0.7239 1.9939)
			(stroke
				(width 0.1)
				(type default)
			)
			(layer "B.Fab")
		)
		(pad "1" smd rect
			(at 0 0 180)
			(size 1.27 1.016)
			(layers "B.Cu" "B.Mask" "B.Paste")
			(net "VR_FET_SW_P12V_STBY_PVDDQ_DEF")
		)
		(pad "2" smd rect
			(at 0 1.778 180)
			(size 1.27 1.016)
			(layers "B.Cu" "B.Mask" "B.Paste")
			(net "GND")
		)
		(zone
			(layer "B.Cu")
			(hatch none 0.5)
			(connect_pads
				(clearance 0)
			)
			(min_thickness 0.25)
			(keepout
				(tracks not_allowed)
				(vias allowed)
				(pads allowed)
				(copperpour not_allowed)
				(footprints allowed)
			)
			(placement
				(enabled no)
				(sheetname "")
			)
			(fill
				(thermal_gap 0.5)
				(thermal_bridge_width 0.5)
				(island_removal_mode 0)
			)
			(polygon
				(pts
					(xy 378.3838 -153.949146) (xy 377.1138 -153.949146) (xy 377.1138 -153.187146) (xy 378.3838 -153.187146)
				)
			)
		)
	)
)
